# BASEBOARD_FAB2 (Tioga Pass) — schematic netlist excerpt (pin names and nets, part order shuffled) for the footprints in the layout excerpt that follows; sources: Cadence DE-HDL packaged netlist, KiCad conversion of Wiwynn_Tioga_Pass_MB.brd

R1M4  RES  100.0 1% CHIP  pkg 0402  page 112 : A = PVCCIO_CPU0 ; B = XDP_CPU_PREQ_N
R2T3  RES  4.75K 1% CHIP  pkg 0402  page 170 : A = P3V3_STBY ; B = FM_FAST_PROCHOT_EN_N
R5P4  RES  49.9 1% CHIP  pkg 0402  page 22 : A = PD_CPU0_RSVD_TEST_2 ; B = GND

(kicad_pcb
	(version 20260206)
	(generator "pcbnew")
	(generator_version "10.0")
	(general
		(thickness 1.6)
		(legacy_teardrops no)
	)
	(paper "A4")
	(title_block
		(title "Wiwynn_Tioga_Pass_MB.brd")
		(comment 1 "Tioga Pass / footprints 2934-2936 of 4770")
	)
	(layers
		(0 "F.Cu" signal "TOP")
		(4 "In1.Cu" signal "L2GND")
		(6 "In2.Cu" signal "L3")
		(8 "In3.Cu" signal "L4GND")
		(10 "In4.Cu" signal "L5")
		(12 "In5.Cu" signal "L6GND")
		(14 "In6.Cu" signal "L7VCC")
		(16 "In7.Cu" signal "L8VCC")
		(18 "In8.Cu" signal "L9GND")
		(20 "In9.Cu" signal "L10")
		(22 "In10.Cu" signal "L11GND")
		(24 "In11.Cu" signal "L12")
		(26 "In12.Cu" signal "L13GND")
		(2 "B.Cu" signal "BOTTOM")
		(9 "F.Adhes" user "F.Adhesive")
		(11 "B.Adhes" user "B.Adhesive")
		(13 "F.Paste" user "Package Geometry/Pastemask Top")
		(15 "B.Paste" user "Package Geometry/Pastemask Bottom")
		(5 "F.SilkS" user "Ref Des/Silkscreen Top")
		(7 "B.SilkS" user "Ref Des/Silkscreen Bottom")
		(1 "F.Mask" user "Board Geometry/Soldermask Top")
		(3 "B.Mask" user "Board Geometry/Soldermask Bottom")
		(17 "Dwgs.User" user "User.Drawings")
		(19 "Cmts.User" user "User.Comments")
		(21 "Eco1.User" user "User.Eco1")
		(23 "Eco2.User" user "User.Eco2")
		(25 "Edge.Cuts" user "Board Geometry/Outline")
		(27 "Margin" user)
		(31 "F.CrtYd" user "Package Geometry/Place Bound Top")
		(29 "B.CrtYd" user "Package Geometry/Place Bound Bottom")
		(35 "F.Fab" user "Ref Des/Assembly Top")
		(33 "B.Fab" user "Ref Des/Assembly Bottom")
	)
	(footprint ""
		(layer "B.Cu")
		(at 418.4142 -74.0537)
		(property "Reference" "R2T3"
			(at 0 0 0)
			(layer "B.SilkS")
			(hide yes)
			(effects
				(font
					(size 1.27 1.27)
				)
				(justify mirror)
			)
		)
		(property "Value" ""
			(at 0 0 0)
			(layer "B.Fab")
			(effects
				(font
					(size 1.27 1.27)
				)
				(justify mirror)
			)
		)
		(duplicate_pad_numbers_are_jumpers no)
		(fp_poly
			(pts
				(xy 0.2794 -0.1016) (xy -0.2794 -0.1016) (xy -0.2794 0.9906) (xy 0.2794 0.9906)
			)
			(stroke
				(width 0)
				(type default)
			)
			(fill no)
			(layer "B.CrtYd")
		)
		(fp_line
			(start -0.2794 -0.1016)
			(end 0.2794 -0.1016)
			(stroke
				(width 0.1)
				(type default)
			)
			(layer "B.Fab")
		)
		(fp_line
			(start -0.2794 0.9906)
			(end -0.2794 -0.1016)
			(stroke
				(width 0.1)
				(type default)
			)
			(layer "B.Fab")
		)
		(fp_line
			(start 0.2794 -0.1016)
			(end 0.2794 0.9906)
			(stroke
				(width 0.1)
				(type default)
			)
			(layer "B.Fab")
		)
		(fp_line
			(start 0.2794 0.9906)
			(end -0.2794 0.9906)
			(stroke
				(width 0.1)
				(type default)
			)
			(layer "B.Fab")
		)
		(pad "1" smd rect
			(at 0 0 180)
			(size 0.508 0.508)
			(layers "B.Cu" "B.Mask" "B.Paste")
			(net "P3V3_STBY")
		)
		(pad "2" smd rect
			(at 0 0.889 180)
			(size 0.508 0.508)
			(layers "B.Cu" "B.Mask" "B.Paste")
			(net "FM_FAST_PROCHOT_EN_N")
		)
		(zone
			(layer "B.Cu")
			(hatch none 0.5)
			(connect_pads
				(clearance 0)
			)
			(min_thickness 0.25)
			(keepout
				(tracks allowed)
				(vias not_allowed)
				(pads allowed)
				(copperpour not_allowed)
				(footprints allowed)
			)
			(placement
				(enabled no)
				(sheetname "")
			)
			(fill
				(thermal_gap 0.5)
				(thermal_bridge_width 0.5)
				(island_removal_mode 0)
			)
			(polygon
				(pts
					(xy 418.6682 -73.7997) (xy 418.1602 -73.7997) (xy 418.1602 -73.4187) (xy 418.6682 -73.4187)
				)
			)
		)
		(zone
			(layer "B.Cu")
			(hatch none 0.5)
			(connect_pads
				(clearance 0)
			)
			(min_thickness 0.25)
			(keepout
				(tracks not_allowed)
				(vias allowed)
				(pads allowed)
				(copperpour not_allowed)
				(footprints allowed)
			)
			(placement
				(enabled no)
				(sheetname "")
			)
			(fill
				(thermal_gap 0.5)
				(thermal_bridge_width 0.5)
				(island_removal_mode 0)
			)
			(polygon
				(pts
					(xy 418.6682 -73.4187) (xy 418.1602 -73.4187) (xy 418.1602 -73.7997) (xy 418.6682 -73.7997)
				)
			)
		)
	)
	(footprint ""
		(layer "B.Cu")
		(at 245.018306 -65.1764 -90)
		(property "Reference" "R5P4"
			(at 0 0 90)
			(layer "B.SilkS")
			(hide yes)
			(effects
				(font
					(size 1.27 1.27)
				)
				(justify mirror)
			)
		)
		(property "Value" ""
			(at 0 0 90)
			(layer "B.Fab")
			(effects
				(font
					(size 1.27 1.27)
				)
				(justify mirror)
			)
		)
		(duplicate_pad_numbers_are_jumpers no)
		(fp_poly
			(pts
				(xy 0.2794 -0.1016) (xy -0.2794 -0.1016) (xy -0.2794 0.9906) (xy 0.2794 0.9906)
			)
			(stroke
				(width 0)
				(type default)
			)
			(fill no)
			(layer "B.CrtYd")
		)
		(fp_line
			(start -0.2794 0.9906)
			(end -0.2794 -0.1016)
			(stroke
				(width 0.1)
				(type default)
			)
			(layer "B.Fab")
		)
		(fp_line
			(start 0.2794 0.9906)
			(end -0.2794 0.9906)
			(stroke
				(width 0.1)
				(type default)
			)
			(layer "B.Fab")
		)
		(fp_line
			(start -0.2794 -0.1016)
			(end 0.2794 -0.1016)
			(stroke
				(width 0.1)
				(type default)
			)
			(layer "B.Fab")
		)
		(fp_line
			(start 0.2794 -0.1016)
			(end 0.2794 0.9906)
			(stroke
				(width 0.1)
				(type default)
			)
			(layer "B.Fab")
		)
		(pad "1" smd rect
			(at 0 0 90)
			(size 0.508 0.508)
			(layers "B.Cu" "B.Mask" "B.Paste")
			(net "PD_CPU0_RSVD_TEST_2")
		)
		(pad "2" smd rect
			(at 0 0.889 90)
			(size 0.508 0.508)
			(layers "B.Cu" "B.Mask" "B.Paste")
			(net "GND")
		)
		(zone
			(layer "B.Cu")
			(hatch none 0.5)
			(connect_pads
				(clearance 0)
			)
			(min_thickness 0.25)
			(keepout
				(tracks not_allowed)
				(vias allowed)
				(pads allowed)
				(copperpour not_allowed)
				(footprints allowed)
			)
			(placement
				(enabled no)
				(sheetname "")
			)
			(fill
				(thermal_gap 0.5)
				(thermal_bridge_width 0.5)
				(island_removal_mode 0)
			)
			(polygon
				(pts
					(xy 244.383306 -64.9224) (xy 244.383306 -65.4304) (xy 244.764306 -65.4304) (xy 244.764306 -64.9224)
				)
			)
		)
		(zone
			(layer "B.Cu")
			(hatch none 0.5)
			(connect_pads
				(clearance 0)
			)
			(min_thickness 0.25)
			(keepout
				(tracks allowed)
				(vias not_allowed)
				(pads allowed)
				(copperpour not_allowed)
				(footprints allowed)
			)
			(placement
				(enabled no)
				(sheetname "")
			)
			(fill
				(thermal_gap 0.5)
				(thermal_bridge_width 0.5)
				(island_removal_mode 0)
			)
			(polygon
				(pts
					(xy 244.764306 -64.9224) (xy 244.764306 -65.4304) (xy 244.383306 -65.4304) (xy 244.383306 -64.9224)
				)
			)
		)
	)
	(footprint ""
		(layer "B.Cu")
		(at 460.388208 -132.842254 -90)
		(property "Reference" "R1M4"
			(at 0 0 90)
			(layer "B.SilkS")
			(hide yes)
			(effects
				(font
					(size 1.27 1.27)
				)
				(justify mirror)
			)
		)
		(property "Value" ""
			(at 0 0 90)
			(layer "B.Fab")
			(effects
				(font
					(size 1.27 1.27)
				)
				(justify mirror)
			)
		)
		(duplicate_pad_numbers_are_jumpers no)
		(fp_poly
			(pts
				(xy 0.2794 -0.1016) (xy -0.2794 -0.1016) (xy -0.2794 0.9906) (xy 0.2794 0.9906)
			)
			(stroke
				(width 0)
				(type default)
			)
			(fill no)
			(layer "B.CrtYd")
		)
		(fp_line
			(start -0.2794 0.9906)
			(end -0.2794 -0.1016)
			(stroke
				(width 0.1)
				(type default)
			)
			(layer "B.Fab")
		)
		(fp_line
			(start 0.2794 0.9906)
			(end -0.2794 0.9906)
			(stroke
				(width 0.1)
				(type default)
			)
			(layer "B.Fab")
		)
		(fp_line
			(start -0.2794 -0.1016)
			(end 0.2794 -0.1016)
			(stroke
				(width 0.1)
				(type default)
			)
			(layer "B.Fab")
		)
		(fp_line
			(start 0.2794 -0.1016)
			(end 0.2794 0.9906)
			(stroke
				(width 0.1)
				(type default)
			)
			(layer "B.Fab")
		)
		(pad "1" smd rect
			(at 0 0 90)
			(size 0.508 0.508)
			(layers "B.Cu" "B.Mask" "B.Paste")
			(net "PVCCIO_CPU0")
		)
		(pad "2" smd rect
			(at 0 0.889 90)
			(size 0.508 0.508)
			(layers "B.Cu" "B.Mask" "B.Paste")
			(net "XDP_CPU_PREQ_N")
		)
		(zone
			(layer "B.Cu")
			(hatch none 0.5)
			(connect_pads
				(clearance 0)
			)
			(min_thickness 0.25)
			(keepout
				(tracks not_allowed)
				(vias allowed)
				(pads allowed)
				(copperpour not_allowed)
				(footprints allowed)
			)
			(placement
				(enabled no)
				(sheetname "")
			)
			(fill
				(thermal_gap 0.5)
				(thermal_bridge_width 0.5)
				(island_removal_mode 0)
			)
			(polygon
				(pts
					(xy 459.753208 -132.588254) (xy 459.753208 -133.096254) (xy 460.134208 -133.096254) (xy 460.134208 -132.588254)
				)
			)
		)
		(zone
			(layer "B.Cu")
			(hatch none 0.5)
			(connect_pads
				(clearance 0)
			)
			(min_thickness 0.25)
			(keepout
				(tracks allowed)
				(vias not_allowed)
				(pads allowed)
				(copperpour not_allowed)
				(footprints allowed)
			)
			(placement
				(enabled no)
				(sheetname "")
			)
			(fill
				(thermal_gap 0.5)
				(thermal_bridge_width 0.5)
				(island_removal_mode 0)
			)
			(polygon
				(pts
					(xy 460.134208 -132.588254) (xy 460.134208 -133.096254) (xy 459.753208 -133.096254) (xy 459.753208 -132.588254)
				)
			)
		)
	)
)
